# S9S_MB_2U (Grand Teton) — schematic netlist excerpt (pin names and nets, part order shuffled) for the footprints in the layout excerpt that follows; sources: Cadence DE-HDL packaged netlist, KiCad conversion of 03242023_DA0F0TMBIJ0_F0T_Motherboard_J_brd_V01_OCP.brd

R324  Q_RES  0 CHIP  pkg 1206LF  page 80 : A = PVNN_MAIN_CPU0 ; B = PVNN_TERM_CPU0
C773  Q_CAP_DIFFBUS  DIFF BUS_0.22UF 6.3V 20% X6S  pkg C0201  page 176 : \1\ = P5E_CPU1_PE2_TX_C_DP<0> ; \2\ = P5E_CPU1_PE2_TX_DP<0>
C2353  Q_CAP  0.1UF 25V 10% EMPTY  pkg 0402  page 167 : A = P2E_MB_BMC_RX_BUF2_C_DP<0> ; B = P2E_MB_BMC_RX_BUF_DP<0>

(kicad_pcb
	(version 20260206)
	(generator "pcbnew")
	(generator_version "10.0")
	(general
		(thickness 1.6)
		(legacy_teardrops no)
	)
	(paper "A4")
	(title_block
		(title "03242023_DA0F0TMBIJ0_F0T_Motherboard_J_brd_V01_OCP.brd")
		(comment 1 "Grand Teton / footprints 2252-2254 of 6105")
	)
	(layers
		(0 "F.Cu" signal "TOP")
		(4 "In1.Cu" signal "GND")
		(6 "In2.Cu" signal "IN1")
		(8 "In3.Cu" signal "GND1")
		(10 "In4.Cu" signal "IN2")
		(12 "In5.Cu" signal "GND2")
		(14 "In6.Cu" signal "IN3")
		(16 "In7.Cu" signal "GND3")
		(18 "In8.Cu" signal "VCC")
		(20 "In9.Cu" signal "VCC1")
		(22 "In10.Cu" signal "GND4")
		(24 "In11.Cu" signal "IN4")
		(26 "In12.Cu" signal "GND5")
		(28 "In13.Cu" signal "IN5")
		(30 "In14.Cu" signal "GND6")
		(32 "In15.Cu" signal "IN6")
		(34 "In16.Cu" signal "GND7")
		(2 "B.Cu" signal "BOTTOM")
		(9 "F.Adhes" user "F.Adhesive")
		(11 "B.Adhes" user "B.Adhesive")
		(13 "F.Paste" user "Package Geometry/Pastemask Top")
		(15 "B.Paste" user "Package Geometry/Pastemask Bottom")
		(5 "F.SilkS" user "Ref Des/Silkscreen Top")
		(7 "B.SilkS" user "Ref Des/Silkscreen Bottom")
		(1 "F.Mask" user "Board Geometry/Soldermask Top")
		(3 "B.Mask" user "Board Geometry/Soldermask Bottom")
		(17 "Dwgs.User" user "User.Drawings")
		(19 "Cmts.User" user "User.Comments")
		(21 "Eco1.User" user "User.Eco1")
		(23 "Eco2.User" user "User.Eco2")
		(25 "Edge.Cuts" user "Board Geometry/Outline")
		(27 "Margin" user)
		(31 "F.CrtYd" user "Package Geometry/Place Bound Top")
		(29 "B.CrtYd" user "Package Geometry/Place Bound Bottom")
		(35 "F.Fab" user "Ref Des/Assembly Top")
		(33 "B.Fab" user "Ref Des/Assembly Bottom")
	)
	(footprint ""
		(layer "F.Cu")
		(at 23.767034 -384.978148 90)
		(property "Reference" "C2353"
			(at 0 0 90)
			(layer "F.SilkS")
			(hide yes)
			(effects
				(font
					(size 1.27 1.27)
				)
			)
		)
		(property "Value" ""
			(at 0 0 90)
			(layer "F.Fab")
			(effects
				(font
					(size 1.27 1.27)
				)
			)
		)
		(duplicate_pad_numbers_are_jumpers no)
		(fp_line
			(start 0.7874 -0.4064)
			(end 0.7874 0.4064)
			(stroke
				(width 0.1524)
				(type default)
			)
			(layer "F.SilkS")
		)
		(fp_line
			(start -0.7874 -0.4064)
			(end -0.036068 -0.4064)
			(stroke
				(width 0.1524)
				(type default)
			)
			(layer "F.SilkS")
		)
		(fp_line
			(start 0.7874 0.4064)
			(end -0.7874 0.4064)
			(stroke
				(width 0.1524)
				(type default)
			)
			(layer "F.SilkS")
		)
		(fp_line
			(start 0.6858 -0.3048)
			(end 0.6858 0.3048)
			(stroke
				(width 0.1)
				(type default)
			)
			(layer "F.Fab")
		)
		(fp_line
			(start 0.1016 -0.3048)
			(end 0.6858 -0.3048)
			(stroke
				(width 0.1)
				(type default)
			)
			(layer "F.Fab")
		)
		(fp_line
			(start -0.1016 -0.3048)
			(end -0.1016 -0.2794)
			(stroke
				(width 0.1)
				(type default)
			)
			(layer "F.Fab")
		)
		(fp_line
			(start -0.6858 -0.3048)
			(end -0.1016 -0.3048)
			(stroke
				(width 0.1)
				(type default)
			)
			(layer "F.Fab")
		)
		(fp_line
			(start 0.1016 -0.2794)
			(end 0.1016 -0.3048)
			(stroke
				(width 0.1)
				(type default)
			)
			(layer "F.Fab")
		)
		(fp_line
			(start -0.1016 -0.2794)
			(end 0.1016 -0.2794)
			(stroke
				(width 0.1)
				(type default)
			)
			(layer "F.Fab")
		)
		(fp_line
			(start 0.1016 0.2794)
			(end -0.1016 0.2794)
			(stroke
				(width 0.1)
				(type default)
			)
			(layer "F.Fab")
		)
		(fp_line
			(start -0.1016 0.2794)
			(end -0.1016 0.3048)
			(stroke
				(width 0.1)
				(type default)
			)
			(layer "F.Fab")
		)
		(fp_line
			(start 0.6858 0.3048)
			(end 0.1016 0.3048)
			(stroke
				(width 0.1)
				(type default)
			)
			(layer "F.Fab")
		)
		(fp_line
			(start 0.1016 0.3048)
			(end 0.1016 0.2794)
			(stroke
				(width 0.1)
				(type default)
			)
			(layer "F.Fab")
		)
		(fp_line
			(start -0.1016 0.3048)
			(end -0.6858 0.3048)
			(stroke
				(width 0.1)
				(type default)
			)
			(layer "F.Fab")
		)
		(fp_line
			(start -0.6858 0.3048)
			(end -0.6858 -0.3048)
			(stroke
				(width 0.1)
				(type default)
			)
			(layer "F.Fab")
		)
		(pad "1" smd rect
			(at -0.40005 0 270)
			(size 0.4572 0.508)
			(layers "F.Cu" "F.Mask" "F.Paste")
			(net "P2E_MB_BMC_RX_BUF2_C_DP<0>")
		)
		(pad "2" smd rect
			(at 0.40005 0 270)
			(size 0.4572 0.508)
			(layers "F.Cu" "F.Mask" "F.Paste")
			(net "P2E_MB_BMC_RX_BUF_DP<0>")
		)
	)
	(footprint ""
		(layer "F.Cu")
		(at 401.62988 -189.067948)
		(property "Reference" "R324"
			(at 0 0 0)
			(layer "F.SilkS")
			(hide yes)
			(effects
				(font
					(size 1.27 1.27)
				)
			)
		)
		(property "Value" ""
			(at 0 0 0)
			(layer "F.Fab")
			(effects
				(font
					(size 1.27 1.27)
				)
			)
		)
		(duplicate_pad_numbers_are_jumpers no)
		(fp_line
			(start -2.044192 -0.94361)
			(end -2.044192 0.898398)
			(stroke
				(width 0.1524)
				(type default)
			)
			(layer "F.SilkS")
		)
		(fp_line
			(start -2.044192 0.94361)
			(end 2.044192 0.94361)
			(stroke
				(width 0.1524)
				(type default)
			)
			(layer "F.SilkS")
		)
		(fp_line
			(start 2.044192 -0.94361)
			(end -2.044192 -0.94361)
			(stroke
				(width 0.1524)
				(type default)
			)
			(layer "F.SilkS")
		)
		(fp_line
			(start 2.044192 0.94361)
			(end 2.044192 -0.94361)
			(stroke
				(width 0.1524)
				(type default)
			)
			(layer "F.SilkS")
		)
		(fp_line
			(start -1.625092 -0.87503)
			(end -1.625092 0.87503)
			(stroke
				(width 0.1)
				(type default)
			)
			(layer "F.Fab")
		)
		(fp_line
			(start -1.625092 0.87503)
			(end 1.625092 0.87503)
			(stroke
				(width 0.1)
				(type default)
			)
			(layer "F.Fab")
		)
		(fp_line
			(start 1.625092 -0.87503)
			(end -1.625092 -0.87503)
			(stroke
				(width 0.1)
				(type default)
			)
			(layer "F.Fab")
		)
		(fp_line
			(start 1.625092 0.87503)
			(end 1.625092 -0.87503)
			(stroke
				(width 0.1)
				(type default)
			)
			(layer "F.Fab")
		)
		(pad "1" smd rect
			(at -1.450086 0)
			(size 0.9144 1.6002)
			(layers "F.Cu" "F.Mask" "F.Paste")
			(net "PVNN_MAIN_CPU0")
		)
		(pad "2" smd rect
			(at 1.450086 0)
			(size 0.9144 1.6002)
			(layers "F.Cu" "F.Mask" "F.Paste")
			(net "PVNN_TERM_CPU0")
		)
	)
	(footprint ""
		(layer "F.Cu")
		(at 166.078154 -402.371052 -90)
		(property "Reference" "C773"
			(at 0 0 270)
			(layer "F.SilkS")
			(hide yes)
			(effects
				(font
					(size 1.27 1.27)
				)
			)
		)
		(property "Value" ""
			(at 0 0 270)
			(layer "F.Fab")
			(effects
				(font
					(size 1.27 1.27)
				)
			)
		)
		(duplicate_pad_numbers_are_jumpers no)
		(fp_line
			(start -0.299974 0.150114)
			(end -0.299974 -0.150114)
			(stroke
				(width 0.1)
				(type default)
			)
			(layer "F.Fab")
		)
		(fp_line
			(start 0.299974 0.150114)
			(end -0.299974 0.150114)
			(stroke
				(width 0.1)
				(type default)
			)
			(layer "F.Fab")
		)
		(fp_line
			(start -0.299974 -0.150114)
			(end 0.299974 -0.150114)
			(stroke
				(width 0.1)
				(type default)
			)
			(layer "F.Fab")
		)
		(fp_line
			(start 0.299974 -0.150114)
			(end 0.299974 0.150114)
			(stroke
				(width 0.1)
				(type default)
			)
			(layer "F.Fab")
		)
		(pad "1" smd rect
			(at -0.2667 0 270)
			(size 0.3048 0.381)
			(layers "F.Cu" "F.Mask" "F.Paste")
			(net "P5E_CPU1_PE2_TX_C_DP<0>")
		)
		(pad "2" smd rect
			(at 0.2667 0 270)
			(size 0.3048 0.381)
			(layers "F.Cu" "F.Mask" "F.Paste")
			(net "P5E_CPU1_PE2_TX_DP<0>")
		)
	)
)
